# S9S_MB_2U (Grand Teton) — schematic netlist excerpt (pin names and nets, part order shuffled) for the footprints in the layout excerpt that follows; sources: Cadence DE-HDL packaged netlist, KiCad conversion of 03242023_DA0F0TMBIJ0_F0T_Motherboard_J_brd_V01_OCP.brd

C1925  Q_CAP  0.1UF 25V 10% X7R  pkg 0402  page 190 : A = P3V3_M2_0 ; B = GND
R252  Q_RES  240 1% CHIP  pkg 0402LF  page 120 : A = PVNN_TERM_CPU0 ; B = PUD_PCH_BOOT_MODE_CPU0

(kicad_pcb
	(version 20260206)
	(generator "pcbnew")
	(generator_version "10.0")
	(general
		(thickness 1.6)
		(legacy_teardrops no)
	)
	(paper "A4")
	(title_block
		(title "03242023_DA0F0TMBIJ0_F0T_Motherboard_J_brd_V01_OCP.brd")
		(comment 1 "Grand Teton / footprints 5792-5793 of 6105")
	)
	(layers
		(0 "F.Cu" signal "TOP")
		(4 "In1.Cu" signal "GND")
		(6 "In2.Cu" signal "IN1")
		(8 "In3.Cu" signal "GND1")
		(10 "In4.Cu" signal "IN2")
		(12 "In5.Cu" signal "GND2")
		(14 "In6.Cu" signal "IN3")
		(16 "In7.Cu" signal "GND3")
		(18 "In8.Cu" signal "VCC")
		(20 "In9.Cu" signal "VCC1")
		(22 "In10.Cu" signal "GND4")
		(24 "In11.Cu" signal "IN4")
		(26 "In12.Cu" signal "GND5")
		(28 "In13.Cu" signal "IN5")
		(30 "In14.Cu" signal "GND6")
		(32 "In15.Cu" signal "IN6")
		(34 "In16.Cu" signal "GND7")
		(2 "B.Cu" signal "BOTTOM")
		(9 "F.Adhes" user "F.Adhesive")
		(11 "B.Adhes" user "B.Adhesive")
		(13 "F.Paste" user "Package Geometry/Pastemask Top")
		(15 "B.Paste" user "Package Geometry/Pastemask Bottom")
		(5 "F.SilkS" user "Ref Des/Silkscreen Top")
		(7 "B.SilkS" user "Ref Des/Silkscreen Bottom")
		(1 "F.Mask" user "Board Geometry/Soldermask Top")
		(3 "B.Mask" user "Board Geometry/Soldermask Bottom")
		(17 "Dwgs.User" user "User.Drawings")
		(19 "Cmts.User" user "User.Comments")
		(21 "Eco1.User" user "User.Eco1")
		(23 "Eco2.User" user "User.Eco2")
		(25 "Edge.Cuts" user "Board Geometry/Outline")
		(27 "Margin" user)
		(31 "F.CrtYd" user "Package Geometry/Place Bound Top")
		(29 "B.CrtYd" user "Package Geometry/Place Bound Bottom")
		(35 "F.Fab" user "Ref Des/Assembly Top")
		(33 "B.Fab" user "Ref Des/Assembly Bottom")
	)
	(footprint ""
		(layer "B.Cu")
		(at 169.66692 -51.399948 180)
		(property "Reference" "C1925"
			(at 0 0 0)
			(layer "B.SilkS")
			(hide yes)
			(effects
				(font
					(size 1.27 1.27)
				)
				(justify mirror)
			)
		)
		(property "Value" ""
			(at 0 0 0)
			(layer "B.Fab")
			(effects
				(font
					(size 1.27 1.27)
				)
				(justify mirror)
			)
		)
		(duplicate_pad_numbers_are_jumpers no)
		(fp_line
			(start 0.7874 0.4064)
			(end 0.7874 -0.4064)
			(stroke
				(width 0.1524)
				(type default)
			)
			(layer "B.SilkS")
		)
		(fp_line
			(start 0.7874 -0.4064)
			(end -0.7874 -0.4064)
			(stroke
				(width 0.1524)
				(type default)
			)
			(layer "B.SilkS")
		)
		(fp_line
			(start -0.7874 0.4064)
			(end 0.7874 0.4064)
			(stroke
				(width 0.1524)
				(type default)
			)
			(layer "B.SilkS")
		)
		(fp_line
			(start -0.7874 -0.4064)
			(end -0.7874 0.4064)
			(stroke
				(width 0.1524)
				(type default)
			)
			(layer "B.SilkS")
		)
		(fp_line
			(start 0.67945 0.3048)
			(end 0.67945 -0.305054)
			(stroke
				(width 0.1)
				(type default)
			)
			(layer "B.Fab")
		)
		(fp_line
			(start 0.67945 -0.305054)
			(end 0.12065 -0.305054)
			(stroke
				(width 0.1)
				(type default)
			)
			(layer "B.Fab")
		)
		(fp_line
			(start 0.12065 0.3048)
			(end 0.67945 0.3048)
			(stroke
				(width 0.1)
				(type default)
			)
			(layer "B.Fab")
		)
		(fp_line
			(start 0.12065 0.2794)
			(end 0.12065 0.3048)
			(stroke
				(width 0.1)
				(type default)
			)
			(layer "B.Fab")
		)
		(fp_line
			(start 0.12065 -0.2794)
			(end -0.12065 -0.2794)
			(stroke
				(width 0.1)
				(type default)
			)
			(layer "B.Fab")
		)
		(fp_line
			(start 0.12065 -0.305054)
			(end 0.12065 -0.2794)
			(stroke
				(width 0.1)
				(type default)
			)
			(layer "B.Fab")
		)
		(fp_line
			(start -0.120396 0.3048)
			(end -0.120396 0.2794)
			(stroke
				(width 0.1)
				(type default)
			)
			(layer "B.Fab")
		)
		(fp_line
			(start -0.120396 0.2794)
			(end 0.12065 0.2794)
			(stroke
				(width 0.1)
				(type default)
			)
			(layer "B.Fab")
		)
		(fp_line
			(start -0.12065 -0.2794)
			(end -0.12065 -0.3048)
			(stroke
				(width 0.1)
				(type default)
			)
			(layer "B.Fab")
		)
		(fp_line
			(start -0.12065 -0.3048)
			(end -0.67945 -0.3048)
			(stroke
				(width 0.1)
				(type default)
			)
			(layer "B.Fab")
		)
		(fp_line
			(start -0.67945 0.3048)
			(end -0.120396 0.3048)
			(stroke
				(width 0.1)
				(type default)
			)
			(layer "B.Fab")
		)
		(fp_line
			(start -0.67945 -0.3048)
			(end -0.67945 0.3048)
			(stroke
				(width 0.1)
				(type default)
			)
			(layer "B.Fab")
		)
		(pad "1" smd circle
			(at 0.40005 0)
			(size 0 0)
			(layers "B.Cu" "B.Mask" "B.Paste")
			(net "P3V3_M2_0")
		)
		(pad "2" smd circle
			(at -0.40005 0)
			(size 0 0)
			(layers "B.Cu" "B.Mask" "B.Paste")
			(net "GND")
		)
	)
	(footprint ""
		(layer "B.Cu")
		(at 405.129238 -193.04381 -90)
		(property "Reference" "R252"
			(at 0 0 90)
			(layer "B.SilkS")
			(hide yes)
			(effects
				(font
					(size 1.27 1.27)
				)
				(justify mirror)
			)
		)
		(property "Value" ""
			(at 0 0 90)
			(layer "B.Fab")
			(effects
				(font
					(size 1.27 1.27)
				)
				(justify mirror)
			)
		)
		(duplicate_pad_numbers_are_jumpers no)
		(fp_line
			(start -0.7874 0.4064)
			(end 0.7874 0.4064)
			(stroke
				(width 0.1524)
				(type default)
			)
			(layer "B.SilkS")
		)
		(fp_line
			(start 0.7874 0.4064)
			(end 0.7874 -0.4064)
			(stroke
				(width 0.1524)
				(type default)
			)
			(layer "B.SilkS")
		)
		(fp_line
			(start -0.7874 -0.4064)
			(end -0.7874 0.4064)
			(stroke
				(width 0.1524)
				(type default)
			)
			(layer "B.SilkS")
		)
		(fp_line
			(start 0.7874 -0.4064)
			(end -0.7874 -0.4064)
			(stroke
				(width 0.1524)
				(type default)
			)
			(layer "B.SilkS")
		)
		(fp_line
			(start -0.67945 0.3048)
			(end -0.120396 0.3048)
			(stroke
				(width 0.1)
				(type default)
			)
			(layer "B.Fab")
		)
		(fp_line
			(start -0.120396 0.3048)
			(end -0.120396 0.2794)
			(stroke
				(width 0.1)
				(type default)
			)
			(layer "B.Fab")
		)
		(fp_line
			(start 0.12065 0.3048)
			(end 0.67945 0.3048)
			(stroke
				(width 0.1)
				(type default)
			)
			(layer "B.Fab")
		)
		(fp_line
			(start 0.67945 0.3048)
			(end 0.67945 -0.305054)
			(stroke
				(width 0.1)
				(type default)
			)
			(layer "B.Fab")
		)
		(fp_line
			(start -0.120396 0.2794)
			(end 0.12065 0.2794)
			(stroke
				(width 0.1)
				(type default)
			)
			(layer "B.Fab")
		)
		(fp_line
			(start 0.12065 0.2794)
			(end 0.12065 0.3048)
			(stroke
				(width 0.1)
				(type default)
			)
			(layer "B.Fab")
		)
		(fp_line
			(start -0.12065 -0.2794)
			(end -0.12065 -0.3048)
			(stroke
				(width 0.1)
				(type default)
			)
			(layer "B.Fab")
		)
		(fp_line
			(start 0.12065 -0.2794)
			(end -0.12065 -0.2794)
			(stroke
				(width 0.1)
				(type default)
			)
			(layer "B.Fab")
		)
		(fp_line
			(start -0.67945 -0.3048)
			(end -0.67945 0.3048)
			(stroke
				(width 0.1)
				(type default)
			)
			(layer "B.Fab")
		)
		(fp_line
			(start -0.12065 -0.3048)
			(end -0.67945 -0.3048)
			(stroke
				(width 0.1)
				(type default)
			)
			(layer "B.Fab")
		)
		(fp_line
			(start 0.12065 -0.305054)
			(end 0.12065 -0.2794)
			(stroke
				(width 0.1)
				(type default)
			)
			(layer "B.Fab")
		)
		(fp_line
			(start 0.67945 -0.305054)
			(end 0.12065 -0.305054)
			(stroke
				(width 0.1)
				(type default)
			)
			(layer "B.Fab")
		)
		(pad "1" smd circle
			(at 0.40005 0 90)
			(size 0 0)
			(layers "B.Cu" "B.Mask" "B.Paste")
			(net "PVNN_TERM_CPU0")
		)
		(pad "2" smd circle
			(at -0.40005 0 90)
			(size 0 0)
			(layers "B.Cu" "B.Mask" "B.Paste")
			(net "PUD_PCH_BOOT_MODE_CPU0")
		)
	)
)
